(kicad_pcb
	(version 20241229)
	(generator "pcbnew")
	(generator_version "9.0")
	(general
		(thickness 1.294)
		(legacy_teardrops no)
	)
	(paper "A3")
	(title_block
		(title "Kintex 410T devboard")
		(date "2024-04-03")
		(rev "1.1.2")
		(comment 9 "footprints 419-422 of 975")
	)
	(layers
		(0 "F.Cu" mixed)
		(4 "In1.Cu" power)
		(6 "In2.Cu" power)
		(8 "In3.Cu" mixed)
		(10 "In4.Cu" power)
		(12 "In5.Cu" mixed)
		(14 "In6.Cu" power)
		(16 "In7.Cu" mixed)
		(18 "In8.Cu" power)
		(2 "B.Cu" mixed)
		(9 "F.Adhes" user "F.Adhesive")
		(11 "B.Adhes" user "B.Adhesive")
		(13 "F.Paste" user)
		(15 "B.Paste" user)
		(5 "F.SilkS" user "F.Silkscreen")
		(7 "B.SilkS" user "B.Silkscreen")
		(1 "F.Mask" user)
		(3 "B.Mask" user)
		(17 "Dwgs.User" user "User.Drawings")
		(19 "Cmts.User" user "User.Comments")
		(21 "Eco1.User" user "User.Eco1")
		(23 "Eco2.User" user "User.Eco2")
		(25 "Edge.Cuts" user)
		(27 "Margin" user)
		(31 "F.CrtYd" user "F.Courtyard")
		(29 "B.CrtYd" user "B.Courtyard")
		(35 "F.Fab" user)
		(33 "B.Fab" user)
	)
	(footprint "antmicro-footprints:C_0402_1005Metric"
		(layer "F.Cu")
		(at 220.8 165.7 180)
		(descr "Capacitor SMD 0402")
		(tags "capacitor SMD 0402")
		(property "Reference" "C164"
			(at -3.65 -0.4 0)
			(layer "F.SilkS")
			(effects
				(font
					(size 0.7 0.7)
					(thickness 0.15)
				)
				(justify right bottom)
			)
		)
		(property "Value" "C_100n_0402"
			(at 0 1.4 0)
			(layer "F.Fab")
			(effects
				(font
					(size 0.7 0.7)
					(thickness 0.15)
				)
				(justify right bottom)
			)
		)
		(property "Description" "SMD Multilayer Ceramic Capacitor, 0.1 µF, 50 V, 0402 [1005 Metric], ± 10%, X5R, GRM Series"
			(at 0 0 180)
			(layer "F.Fab")
			(hide yes)
			(effects
				(font
					(size 1.27 1.27)
					(thickness 0.15)
				)
			)
		)
		(property "Author" "Antmicro"
			(at 441.6 331.4 0)
			(layer "F.Fab")
			(hide yes)
			(effects
				(font
					(size 1 1)
					(thickness 0.15)
				)
			)
		)
		(property "Dielectric" "X5R"
			(at 441.6 331.4 0)
			(layer "F.Fab")
			(hide yes)
			(effects
				(font
					(size 1 1)
					(thickness 0.15)
				)
			)
		)
		(property "License" "Apache-2.0"
			(at 441.6 331.4 0)
			(layer "F.Fab")
			(hide yes)
			(effects
				(font
					(size 1 1)
					(thickness 0.15)
				)
			)
		)
		(property "MPN" "GRM155R61H104KE14D"
			(at 441.6 331.4 0)
			(layer "F.Fab")
			(hide yes)
			(effects
				(font
					(size 1 1)
					(thickness 0.15)
				)
			)
		)
		(property "Manufacturer" "Murata"
			(at 441.6 331.4 0)
			(layer "F.Fab")
			(hide yes)
			(effects
				(font
					(size 1 1)
					(thickness 0.15)
				)
			)
		)
		(property "Val" "100n"
			(at 441.6 331.4 0)
			(layer "F.Fab")
			(hide yes)
			(effects
				(font
					(size 1 1)
					(thickness 0.15)
				)
			)
		)
		(property "Voltage" "50V"
			(at 441.6 331.4 0)
			(layer "F.Fab")
			(hide yes)
			(effects
				(font
					(size 1 1)
					(thickness 0.15)
				)
			)
		)
		(sheetname "FPGA Config")
		(sheetfile "fpga-config.kicad_sch")
		(attr smd)
		(fp_rect
			(start -0.925 -0.47)
			(end 0.925 0.47)
			(stroke
				(width 0.05)
				(type default)
			)
			(fill no)
			(layer "F.CrtYd")
		)
		(fp_line
			(start 0.504 0.248)
			(end -0.494 0.248)
			(stroke
				(width 0.15)
				(type solid)
			)
			(layer "F.Fab")
		)
		(fp_line
			(start 0.504 -0.25)
			(end 0.504 0.248)
			(stroke
				(width 0.15)
				(type solid)
			)
			(layer "F.Fab")
		)
		(fp_line
			(start -0.494 0.248)
			(end -0.494 -0.25)
			(stroke
				(width 0.15)
				(type solid)
			)
			(layer "F.Fab")
		)
		(fp_line
			(start -0.494 -0.25)
			(end 0.504 -0.25)
			(stroke
				(width 0.15)
				(type solid)
			)
			(layer "F.Fab")
		)
		(pad "1" smd roundrect
			(at -0.48 0 180)
			(size 0.59 0.64)
			(layers "F.Cu" "F.Mask" "F.Paste")
			(roundrect_rratio 0.25)
			(net 1 "GND")
			(pintype "passive")
		)
		(pad "2" smd roundrect
			(at 0.48 0 180)
			(size 0.59 0.64)
			(layers "F.Cu" "F.Mask" "F.Paste")
			(roundrect_rratio 0.25)
			(net 24 "+3V3")
			(pintype "passive")
		)
	)
	(footprint "antmicro-footprints:L_Bourns-SRP6050CA"
		(layer "F.Cu")
		(at 200.5 159.424 90)
		(property "Reference" "L1"
			(at -4.376 2.2 180)
			(layer "F.SilkS")
			(effects
				(font
					(size 0.7 0.7)
					(thickness 0.15)
				)
				(justify left bottom)
			)
		)
		(property "Value" "L_1u5_17A_Bourns-SRP6050CA"
			(at -5.41 4.27 90)
			(layer "F.Fab")
			(effects
				(font
					(size 0.7 0.7)
					(thickness 0.15)
				)
				(justify left bottom)
			)
		)
		(property "Description" "Power Inductor (SMT), 1.5 µH, 17 A, Shielded, 19.5 A, SRP6050CA"
			(at 0 0 90)
			(layer "F.Fab")
			(hide yes)
			(effects
				(font
					(size 1.27 1.27)
					(thickness 0.15)
				)
			)
		)
		(property "Author" "Antmicro"
			(at 359.924 -41.076 0)
			(layer "F.Fab")
			(hide yes)
			(effects
				(font
					(size 1 1)
					(thickness 0.15)
				)
			)
		)
		(property "IMax" "17 A"
			(at 359.924 -41.076 0)
			(layer "F.Fab")
			(hide yes)
			(effects
				(font
					(size 1 1)
					(thickness 0.15)
				)
			)
		)
		(property "ISat" "19.5 A"
			(at 359.924 -41.076 0)
			(layer "F.Fab")
			(hide yes)
			(effects
				(font
					(size 1 1)
					(thickness 0.15)
				)
			)
		)
		(property "License" "Apache-2.0"
			(at 359.924 -41.076 0)
			(layer "F.Fab")
			(hide yes)
			(effects
				(font
					(size 1 1)
					(thickness 0.15)
				)
			)
		)
		(property "MPN" "SRP6050CA-1R5M"
			(at 359.924 -41.076 0)
			(layer "F.Fab")
			(hide yes)
			(effects
				(font
					(size 1 1)
					(thickness 0.15)
				)
			)
		)
		(property "Manufacturer" "Bourns"
			(at 359.924 -41.076 0)
			(layer "F.Fab")
			(hide yes)
			(effects
				(font
					(size 1 1)
					(thickness 0.15)
				)
			)
		)
		(property "Size" "6.6x6.6"
			(at 359.924 -41.076 0)
			(layer "F.Fab")
			(hide yes)
			(effects
				(font
					(size 1 1)
					(thickness 0.15)
				)
			)
		)
		(property "Val" "1u5/17A"
			(at 359.924 -41.076 0)
			(layer "F.Fab")
			(hide yes)
			(effects
				(font
					(size 1 1)
					(thickness 0.15)
				)
			)
		)
		(sheetname "DC-DC Converters")
		(sheetfile "dc-dc.kicad_sch")
		(attr smd)
		(fp_line
			(start 3.2 -3.301)
			(end 3.2 3.298)
			(stroke
				(width 0.15)
				(type solid)
			)
			(layer "F.SilkS")
		)
		(fp_line
			(start -3.2 -3.301)
			(end 3.2 -3.301)
			(stroke
				(width 0.15)
				(type solid)
			)
			(layer "F.SilkS")
		)
		(fp_line
			(start -3.2 -3.301)
			(end -3.2 3.298)
			(stroke
				(width 0.15)
				(type solid)
			)
			(layer "F.SilkS")
		)
		(fp_line
			(start 3.2 3.298)
			(end -3.2 3.298)
			(stroke
				(width 0.15)
				(type solid)
			)
			(layer "F.SilkS")
		)
		(fp_rect
			(start -3.45 -3.55)
			(end 3.45 3.55)
			(stroke
				(width 0.05)
				(type solid)
			)
			(fill no)
			(layer "F.CrtYd")
		)
		(fp_rect
			(start -3.202 -3.301)
			(end 3.2 3.298)
			(stroke
				(width 0.15)
				(type solid)
			)
			(fill no)
			(layer "F.Fab")
		)
		(pad "1" smd roundrect
			(at -2.025 0 90)
			(size 1.55 5.6)
			(layers "F.Cu" "F.Mask" "F.Paste")
			(roundrect_rratio 0.1)
			(net 746 "/DC-DC Converters/1V0_SW")
			(pintype "passive")
		)
		(pad "2" smd roundrect
			(at 2.025 0 90)
			(size 1.55 5.6)
			(layers "F.Cu" "F.Mask" "F.Paste")
			(roundrect_rratio 0.1)
			(net 751 "/DC-DC Converters/1V0_REG")
			(pintype "passive")
		)
	)
	(footprint "antmicro-footprints:SC70-3"
		(layer "F.Cu")
		(at 258.4 88.6)
		(property "Reference" "Q10"
			(at -1.6 1.1 90)
			(layer "F.SilkS")
			(effects
				(font
					(size 0.7 0.7)
					(thickness 0.15)
				)
				(justify left bottom)
			)
		)
		(property "Value" "BSS138PW"
			(at 0 2.3 0)
			(layer "F.Fab")
			(effects
				(font
					(size 0.7 0.7)
					(thickness 0.15)
				)
				(justify left bottom)
			)
		)
		(property "Description" "Power MOSFET, N Channel, 60 V, 320 mA, 0.9 ohm, SOT-323, Surface Mount"
			(at 0 0 0)
			(layer "F.Fab")
			(hide yes)
			(effects
				(font
					(size 1.27 1.27)
					(thickness 0.15)
				)
			)
		)
		(property "Author" "Antmicro"
			(at 0 0 0)
			(layer "F.Fab")
			(hide yes)
			(effects
				(font
					(size 1 1)
					(thickness 0.15)
				)
			)
		)
		(property "License" "Apache-2.0"
			(at 0 0 0)
			(layer "F.Fab")
			(hide yes)
			(effects
				(font
					(size 1 1)
					(thickness 0.15)
				)
			)
		)
		(property "MPN" "BSS138PW"
			(at 0 0 0)
			(layer "F.Fab")
			(hide yes)
			(effects
				(font
					(size 1 1)
					(thickness 0.15)
				)
			)
		)
		(property "Manufacturer" "Nexperia"
			(at 0 0 0)
			(layer "F.Fab")
			(hide yes)
			(effects
				(font
					(size 1 1)
					(thickness 0.15)
				)
			)
		)
		(sheetname "User GPIO + LED + button + DIP switch")
		(sheetfile "user-gpio.kicad_sch")
		(attr smd)
		(fp_line
			(start -0.3 -1)
			(end 0.627 -0.999)
			(stroke
				(width 0.15)
				(type solid)
			)
			(layer "F.SilkS")
		)
		(fp_line
			(start -0.3 1)
			(end 0.627 1.001)
			(stroke
				(width 0.15)
				(type solid)
			)
			(layer "F.SilkS")
		)
		(fp_line
			(start 0.627 -0.6)
			(end 0.627 -0.999)
			(stroke
				(width 0.15)
				(type solid)
			)
			(layer "F.SilkS")
		)
		(fp_line
			(start 0.627 0.6)
			(end 0.627 1.001)
			(stroke
				(width 0.15)
				(type solid)
			)
			(layer "F.SilkS")
		)
		(fp_line
			(start -1.4 1)
			(end -1.4 -1)
			(stroke
				(width 0.05)
				(type solid)
			)
			(layer "F.CrtYd")
		)
		(fp_line
			(start -0.9 -1.3)
			(end -0.9 -1)
			(stroke
				(width 0.05)
				(type solid)
			)
			(layer "F.CrtYd")
		)
		(fp_line
			(start -0.9 -1.3)
			(end 0.9 -1.3)
			(stroke
				(width 0.05)
				(type solid)
			)
			(layer "F.CrtYd")
		)
		(fp_line
			(start -0.9 -1)
			(end -1.4 -1)
			(stroke
				(width 0.05)
				(type solid)
			)
			(layer "F.CrtYd")
		)
		(fp_line
			(start -0.9 1)
			(end -1.4 1)
			(stroke
				(width 0.05)
				(type solid)
			)
			(layer "F.CrtYd")
		)
		(fp_line
			(start -0.9 1.3)
			(end -0.9 1)
			(stroke
				(width 0.05)
				(type solid)
			)
			(layer "F.CrtYd")
		)
		(fp_line
			(start 0.9 -1.3)
			(end 0.9 -0.4)
			(stroke
				(width 0.05)
				(type solid)
			)
			(layer "F.CrtYd")
		)
		(fp_line
			(start 0.9 -0.4)
			(end 1.4 -0.4)
			(stroke
				(width 0.05)
				(type solid)
			)
			(layer "F.CrtYd")
		)
		(fp_line
			(start 0.9 0.4)
			(end 0.9 1.3)
			(stroke
				(width 0.05)
				(type solid)
			)
			(layer "F.CrtYd")
		)
		(fp_line
			(start 0.9 1.3)
			(end -0.9 1.3)
			(stroke
				(width 0.05)
				(type solid)
			)
			(layer "F.CrtYd")
		)
		(fp_line
			(start 1.4 -0.4)
			(end 1.4 0.4)
			(stroke
				(width 0.05)
				(type solid)
			)
			(layer "F.CrtYd")
		)
		(fp_line
			(start 1.4 0.4)
			(end 0.9 0.4)
			(stroke
				(width 0.05)
				(type solid)
			)
			(layer "F.CrtYd")
		)
		(fp_rect
			(start -0.623 -0.999)
			(end 0.627 1.001)
			(stroke
				(width 0.15)
				(type solid)
			)
			(fill no)
			(layer "F.Fab")
		)
		(pad "1" smd rect
			(at -1.051 -0.65 90)
			(size 0.6 0.6)
			(layers "F.Cu" "F.Mask" "F.Paste")
			(net 1301 "/USER_IO.LED_GREEN2")
			(pinfunction "G")
			(pintype "passive")
		)
		(pad "2" smd rect
			(at -1.051 0.65 90)
			(size 0.6 0.6)
			(layers "F.Cu" "F.Mask" "F.Paste")
			(net 1 "GND")
			(pinfunction "S")
			(pintype "passive")
		)
		(pad "3" smd rect
			(at 1.05 0 90)
			(size 0.6 0.6)
			(layers "F.Cu" "F.Mask" "F.Paste")
			(net 22 "Net-(D20-C)")
			(pinfunction "D")
			(pintype "passive")
		)
	)
	(footprint "antmicro-footprints:LED_0603_1608Metric_G"
		(layer "F.Cu")
		(at 209.52 74.97 90)
		(descr "LED SMD 0603 Green")
		(tags "LED SMD 0603 Green")
		(property "Reference" "D2"
			(at -2.23 0.78 0)
			(layer "F.SilkS")
			(effects
				(font
					(size 0.7 0.7)
					(thickness 0.15)
				)
				(justify right bottom)
			)
		)
		(property "Value" "LED_G_0603_KP-1608CGCK"
			(at 0 1.6 90)
			(layer "F.Fab")
			(effects
				(font
					(size 0.7 0.7)
					(thickness 0.15)
				)
				(justify left bottom)
			)
		)
		(property "Description" "LED, Green, SMD, 0603, 20 mA, 2.1 V, 570 nm"
			(at 0 0 90)
			(layer "F.Fab")
			(hide yes)
			(effects
				(font
					(size 1.27 1.27)
					(thickness 0.15)
				)
			)
		)
		(property "Author" "Antmicro"
			(at 284.49 -134.55 0)
			(layer "F.Fab")
			(hide yes)
			(effects
				(font
					(size 1 1)
					(thickness 0.15)
				)
			)
		)
		(property "Color" "Green"
			(at 284.49 -134.55 0)
			(layer "F.Fab")
			(hide yes)
			(effects
				(font
					(size 1 1)
					(thickness 0.15)
				)
			)
		)
		(property "License" "Apache-2.0"
			(at 284.49 -134.55 0)
			(layer "F.Fab")
			(hide yes)
			(effects
				(font
					(size 1 1)
					(thickness 0.15)
				)
			)
		)
		(property "MPN" "KP-1608CGCK"
			(at 284.49 -134.55 0)
			(layer "F.Fab")
			(hide yes)
			(effects
				(font
					(size 1 1)
					(thickness 0.15)
				)
			)
		)
		(property "Manufacturer" "Kingbright"
			(at 284.49 -134.55 0)
			(layer "F.Fab")
			(hide yes)
			(effects
				(font
					(size 1 1)
					(thickness 0.15)
				)
			)
		)
		(sheetname "FPGA Config")
		(sheetfile "fpga-config.kicad_sch")
		(attr smd)
		(fp_line
			(start 0.22 -0.35)
			(end -0.22 -0.35)
			(stroke
				(width 0.15)
				(type solid)
			)
			(layer "F.SilkS")
		)
		(fp_line
			(start -1.18 -0.319)
			(end -1.18 0.321)
			(stroke
				(width 0.15)
				(type solid)
			)
			(layer "F.SilkS")
		)
		(fp_line
			(start 0.105328 0.001008)
			(end 0.24 0.001)
			(stroke
				(width 0.1)
				(type solid)
			)
			(layer "F.SilkS")
		)
		(fp_line
			(start -0.094672 0.001008)
			(end 0.105328 -0.198992)
			(stroke
				(width 0.1)
				(type solid)
			)
			(layer "F.SilkS")
		)
		(fp_line
			(start -0.094672 0.001008)
			(end -0.24 0.001008)
			(stroke
				(width 0.1)
				(type solid)
			)
			(layer "F.SilkS")
		)
		(fp_line
			(start 0.105328 0.201008)
			(end 0.105328 -0.198992)
			(stroke
				(width 0.1)
				(type solid)
			)
			(layer "F.SilkS")
		)
		(fp_line
			(start 0.105328 0.201008)
			(end -0.094672 0.001008)
			(stroke
				(width 0.1)
				(type solid)
			)
			(layer "F.SilkS")
		)
		(fp_line
			(start -0.094672 0.201008)
			(end -0.094672 -0.198992)
			(stroke
				(width 0.1)
				(type solid)
			)
			(layer "F.SilkS")
		)
		(fp_line
			(start 0.22 0.35)
			(end -0.22 0.35)
			(stroke
				(width 0.15)
				(type solid)
			)
			(layer "F.SilkS")
		)
		(fp_rect
			(start 1.25 0.65)
			(end -1.25 -0.65)
			(stroke
				(width 0.05)
				(type solid)
			)
			(fill no)
			(layer "F.CrtYd")
		)
		(fp_line
			(start 0.201 -0.202)
			(end -0.101 0)
			(stroke
				(width 0.15)
				(type solid)
			)
			(layer "F.Fab")
		)
		(fp_line
			(start -0.199 -0.202)
			(end -0.199 0.1)
			(stroke
				(width 0.15)
				(type solid)
			)
			(layer "F.Fab")
		)
		(fp_line
			(start 0.599 0)
			(end 0.201 0)
			(stroke
				(width 0.15)
				(type solid)
			)
			(layer "F.Fab")
		)
		(fp_line
			(start 0.201 0)
			(end 0.201 -0.202)
			(stroke
				(width 0.15)
				(type solid)
			)
			(layer "F.Fab")
		)
		(fp_line
			(start -0.101 0)
			(end 0.201 0.2)
			(stroke
				(width 0.15)
				(type solid)
			)
			(layer "F.Fab")
		)
		(fp_line
			(start -0.199 0)
			(end -0.597 0)
			(stroke
				(width 0.15)
				(type solid)
			)
			(layer "F.Fab")
		)
		(fp_line
			(start 0.201 0.2)
			(end 0.201 0)
			(stroke
				(width 0.15)
				(type solid)
			)
			(layer "F.Fab")
		)
		(fp_line
			(start -0.199 0.2)
			(end -0.199 0.1)
			(stroke
				(width 0.15)
				(type solid)
			)
			(layer "F.Fab")
		)
		(fp_rect
			(start 0.848 0.4)
			(end -0.85 -0.402)
			(stroke
				(width 0.15)
				(type solid)
			)
			(fill no)
			(layer "F.Fab")
		)
		(pad "1" smd roundrect
			(at -0.7 0 270)
			(size 0.8 1)
			(layers "F.Cu" "F.Mask" "F.Paste")
			(roundrect_rratio 0.2)
			(net 754 "Net-(D2-C)")
			(pinfunction "C")
			(pintype "passive")
		)
		(pad "2" smd roundrect
			(at 0.7 0 270)
			(size 0.8 1)
			(layers "F.Cu" "F.Mask" "F.Paste")
			(roundrect_rratio 0.2)
			(net 24 "+3V3")
			(pinfunction "A")
			(pintype "passive")
		)
	)
)
